(kicad_pcb
	(version 20260206)
	(generator "pcbnew")
	(generator_version "10.0")
	(general
		(thickness 1.6)
		(legacy_teardrops no)
	)
	(paper "A4")
	(title_block
		(title "v2-tray-backplane — ms_tbp_v2.brd")
		(comment 1 "Open CloudServer (Microsoft) / footprint 95 of 164 (J12), pads 1-84 of 84")
	)
	(layers
		(0 "F.Cu" signal "TOP")
		(4 "In1.Cu" signal "LYR2")
		(6 "In2.Cu" signal "LYR3")
		(8 "In3.Cu" signal "LYR4")
		(10 "In4.Cu" signal "LYR5")
		(12 "In5.Cu" signal "LYR6")
		(14 "In6.Cu" signal "LYR7")
		(2 "B.Cu" signal "BOTTOM")
		(9 "F.Adhes" user "F.Adhesive")
		(11 "B.Adhes" user "B.Adhesive")
		(13 "F.Paste" user "Package Geometry/Pastemask Top")
		(15 "B.Paste" user "Package Geometry/Pastemask Bottom")
		(5 "F.SilkS" user "Ref Des/Silkscreen Top")
		(7 "B.SilkS" user "Ref Des/Silkscreen Bottom")
		(1 "F.Mask" user "Board Geometry/Soldermask Top")
		(3 "B.Mask" user "Board Geometry/Soldermask Bottom")
		(17 "Dwgs.User" user "User.Drawings")
		(19 "Cmts.User" user "User.Comments")
		(21 "Eco1.User" user "User.Eco1")
		(23 "Eco2.User" user "User.Eco2")
		(25 "Edge.Cuts" user "Board Geometry/Outline")
		(27 "Margin" user)
		(31 "F.CrtYd" user "Package Geometry/Place Bound Top")
		(29 "B.CrtYd" user "Package Geometry/Place Bound Bottom")
		(35 "F.Fab" user "Ref Des/Assembly Top")
		(33 "B.Fab" user "Ref Des/Assembly Bottom")
	)
	(footprint ""
		(layer "F.Cu")
		(at -240.850001 13.639371 180)
		(property "Reference" "J12"
			(at 8.500001 -13.9151 0)
			(unlocked yes)
			(layer "F.SilkS")
			(effects
				(font
					(size 0.762 0.5334)
					(thickness 0.1016)
				)
			)
		)
		(property "Value" ""
			(at 0 0 180)
			(layer "F.Fab")
			(effects
				(font
					(size 1.27 1.27)
				)
			)
		)
		(duplicate_pad_numbers_are_jumpers no)
		(pad "" thru_hole circle
			(at 2.999999 4.399999 180)
			(size 3.81 3.81)
			(drill 2.2098)
			(layers "*.Cu" "*.Mask")
			(remove_unused_layers no)
		)
		(pad "" thru_hole circle
			(at 14 4.399999 180)
			(size 3.81 3.81)
			(drill 2.2098)
			(layers "*.Cu" "*.Mask")
			(remove_unused_layers no)
		)
		(pad "1" thru_hole circle
			(at 1.5 -13.109999 180)
			(size 1.1176 1.1176)
			(drill 0.6096)
			(layers "*.Cu" "*.Mask")
			(remove_unused_layers no)
			(net "GND")
		)
		(pad "1A1" thru_hole circle
			(at 0 0 180)
			(size 0.6858 0.6858)
			(drill 0.381)
			(layers "*.Cu" "*.Mask")
			(remove_unused_layers no)
			(net "Net_409")
		)
		(pad "1A2" thru_hole circle
			(at 0.750001 1.4 180)
			(size 0.6858 0.6858)
			(drill 0.381)
			(layers "*.Cu" "*.Mask")
			(remove_unused_layers no)
			(net "Net_408")
		)
		(pad "1A3" thru_hole circle
			(at 1.5 0.700001 180)
			(size 0.6858 0.6858)
			(drill 0.381)
			(layers "*.Cu" "*.Mask")
			(remove_unused_layers no)
			(net "GND")
		)
		(pad "1A4" thru_hole circle
			(at 2.250001 0 180)
			(size 0.6858 0.6858)
			(drill 0.381)
			(layers "*.Cu" "*.Mask")
			(remove_unused_layers no)
			(net "SAS_B1_RX2P")
		)
		(pad "1A5" thru_hole circle
			(at 2.999999 1.4 180)
			(size 0.6858 0.6858)
			(drill 0.381)
			(layers "*.Cu" "*.Mask")
			(remove_unused_layers no)
			(net "SAS_B1_RX2N")
		)
		(pad "1A6" thru_hole circle
			(at 3.75 0.700001 180)
			(size 0.6858 0.6858)
			(drill 0.381)
			(layers "*.Cu" "*.Mask")
			(remove_unused_layers no)
			(net "GND")
		)
		(pad "1A7" thru_hole circle
			(at 4.500001 0 180)
			(size 0.6858 0.6858)
			(drill 0.381)
			(layers "*.Cu" "*.Mask")
			(remove_unused_layers no)
			(net "SAS_B1_RX4P")
		)
		(pad "1A8" thru_hole circle
			(at 5.25 1.4 180)
			(size 0.6858 0.6858)
			(drill 0.381)
			(layers "*.Cu" "*.Mask")
			(remove_unused_layers no)
			(net "SAS_B1_RX4N")
		)
		(pad "1A9" thru_hole circle
			(at 6.000001 0.700001 180)
			(size 0.6858 0.6858)
			(drill 0.381)
			(layers "*.Cu" "*.Mask")
			(remove_unused_layers no)
			(net "GND")
		)
		(pad "1B1" thru_hole circle
			(at 0 -3.8 180)
			(size 0.6858 0.6858)
			(drill 0.381)
			(layers "*.Cu" "*.Mask")
			(remove_unused_layers no)
			(net "Net_407")
		)
		(pad "1B2" thru_hole circle
			(at 0.750001 -2.4 180)
			(size 0.6858 0.6858)
			(drill 0.381)
			(layers "*.Cu" "*.Mask")
			(remove_unused_layers no)
			(net "Net_406")
		)
		(pad "1B3" thru_hole circle
			(at 1.5 -3.099999 180)
			(size 0.6858 0.6858)
			(drill 0.381)
			(layers "*.Cu" "*.Mask")
			(remove_unused_layers no)
			(net "GND")
		)
		(pad "1B4" thru_hole circle
			(at 2.250001 -3.8 180)
			(size 0.6858 0.6858)
			(drill 0.381)
			(layers "*.Cu" "*.Mask")
			(remove_unused_layers no)
			(net "SAS_B1_RX1P")
		)
		(pad "1B5" thru_hole circle
			(at 2.999999 -2.4 180)
			(size 0.6858 0.6858)
			(drill 0.381)
			(layers "*.Cu" "*.Mask")
			(remove_unused_layers no)
			(net "SAS_B1_RX1N")
		)
		(pad "1B6" thru_hole circle
			(at 3.75 -3.099999 180)
			(size 0.6858 0.6858)
			(drill 0.381)
			(layers "*.Cu" "*.Mask")
			(remove_unused_layers no)
			(net "GND")
		)
		(pad "1B7" thru_hole circle
			(at 4.500001 -3.8 180)
			(size 0.6858 0.6858)
			(drill 0.381)
			(layers "*.Cu" "*.Mask")
			(remove_unused_layers no)
			(net "SAS_B1_RX3P")
		)
		(pad "1B8" thru_hole circle
			(at 5.25 -2.4 180)
			(size 0.6858 0.6858)
			(drill 0.381)
			(layers "*.Cu" "*.Mask")
			(remove_unused_layers no)
			(net "SAS_B1_RX3N")
		)
		(pad "1B9" thru_hole circle
			(at 6.000001 -3.099999 180)
			(size 0.6858 0.6858)
			(drill 0.381)
			(layers "*.Cu" "*.Mask")
			(remove_unused_layers no)
			(net "GND")
		)
		(pad "1C1" thru_hole circle
			(at 0 -7.6 180)
			(size 0.6858 0.6858)
			(drill 0.381)
			(layers "*.Cu" "*.Mask")
			(remove_unused_layers no)
			(net "Net_405")
		)
		(pad "1C2" thru_hole circle
			(at 0.750001 -6.2 180)
			(size 0.6858 0.6858)
			(drill 0.381)
			(layers "*.Cu" "*.Mask")
			(remove_unused_layers no)
			(net "Net_404")
		)
		(pad "1C3" thru_hole circle
			(at 1.5 -6.899999 180)
			(size 0.6858 0.6858)
			(drill 0.381)
			(layers "*.Cu" "*.Mask")
			(remove_unused_layers no)
			(net "GND")
		)
		(pad "1C4" thru_hole circle
			(at 2.250001 -7.6 180)
			(size 0.6858 0.6858)
			(drill 0.381)
			(layers "*.Cu" "*.Mask")
			(remove_unused_layers no)
			(net "SAS_B1_TX2P")
		)
		(pad "1C5" thru_hole circle
			(at 2.999999 -6.2 180)
			(size 0.6858 0.6858)
			(drill 0.381)
			(layers "*.Cu" "*.Mask")
			(remove_unused_layers no)
			(net "SAS_B1_TX2N")
		)
		(pad "1C6" thru_hole circle
			(at 3.75 -6.899999 180)
			(size 0.6858 0.6858)
			(drill 0.381)
			(layers "*.Cu" "*.Mask")
			(remove_unused_layers no)
			(net "GND")
		)
		(pad "1C7" thru_hole circle
			(at 4.500001 -7.6 180)
			(size 0.6858 0.6858)
			(drill 0.381)
			(layers "*.Cu" "*.Mask")
			(remove_unused_layers no)
			(net "SAS_B1_TX4P")
		)
		(pad "1C8" thru_hole circle
			(at 5.25 -6.2 180)
			(size 0.6858 0.6858)
			(drill 0.381)
			(layers "*.Cu" "*.Mask")
			(remove_unused_layers no)
			(net "SAS_B1_TX4N")
		)
		(pad "1C9" thru_hole circle
			(at 6.000001 -6.899999 180)
			(size 0.6858 0.6858)
			(drill 0.381)
			(layers "*.Cu" "*.Mask")
			(remove_unused_layers no)
			(net "GND")
		)
		(pad "1D1" thru_hole circle
			(at 0 -11.4 180)
			(size 0.6858 0.6858)
			(drill 0.381)
			(layers "*.Cu" "*.Mask")
			(remove_unused_layers no)
			(net "Net_403")
		)
		(pad "1D2" thru_hole circle
			(at 0.750001 -10 180)
			(size 0.6858 0.6858)
			(drill 0.381)
			(layers "*.Cu" "*.Mask")
			(remove_unused_layers no)
			(net "Net_402")
		)
		(pad "1D3" thru_hole circle
			(at 1.5 -10.699999 180)
			(size 0.6858 0.6858)
			(drill 0.381)
			(layers "*.Cu" "*.Mask")
			(remove_unused_layers no)
			(net "GND")
		)
		(pad "1D4" thru_hole circle
			(at 2.250001 -11.4 180)
			(size 0.6858 0.6858)
			(drill 0.381)
			(layers "*.Cu" "*.Mask")
			(remove_unused_layers no)
			(net "SAS_B1_TX1P")
		)
		(pad "1D5" thru_hole circle
			(at 2.999999 -10 180)
			(size 0.6858 0.6858)
			(drill 0.381)
			(layers "*.Cu" "*.Mask")
			(remove_unused_layers no)
			(net "SAS_B1_TX1N")
		)
		(pad "1D6" thru_hole circle
			(at 3.75 -10.699999 180)
			(size 0.6858 0.6858)
			(drill 0.381)
			(layers "*.Cu" "*.Mask")
			(remove_unused_layers no)
			(net "GND")
		)
		(pad "1D7" thru_hole circle
			(at 4.500001 -11.4 180)
			(size 0.6858 0.6858)
			(drill 0.381)
			(layers "*.Cu" "*.Mask")
			(remove_unused_layers no)
			(net "SAS_B1_TX3P")
		)
		(pad "1D8" thru_hole circle
			(at 5.25 -10 180)
			(size 0.6858 0.6858)
			(drill 0.381)
			(layers "*.Cu" "*.Mask")
			(remove_unused_layers no)
			(net "SAS_B1_TX3N")
		)
		(pad "1D9" thru_hole circle
			(at 6.000001 -10.699999 180)
			(size 0.6858 0.6858)
			(drill 0.381)
			(layers "*.Cu" "*.Mask")
			(remove_unused_layers no)
			(net "GND")
		)
		(pad "2" thru_hole circle
			(at 6.000001 -13.109999 180)
			(size 1.1176 1.1176)
			(drill 0.6096)
			(layers "*.Cu" "*.Mask")
			(remove_unused_layers no)
			(net "GND")
		)
		(pad "2A1" thru_hole circle
			(at 11.000001 0 180)
			(size 0.6858 0.6858)
			(drill 0.381)
			(layers "*.Cu" "*.Mask")
			(remove_unused_layers no)
			(net "Net_401")
		)
		(pad "2A2" thru_hole circle
			(at 11.749999 1.4 180)
			(size 0.6858 0.6858)
			(drill 0.381)
			(layers "*.Cu" "*.Mask")
			(remove_unused_layers no)
			(net "Net_400")
		)
		(pad "2A3" thru_hole circle
			(at 12.5 0.700001 180)
			(size 0.6858 0.6858)
			(drill 0.381)
			(layers "*.Cu" "*.Mask")
			(remove_unused_layers no)
			(net "GND")
		)
		(pad "2A4" thru_hole circle
			(at 13.249999 0 180)
			(size 0.6858 0.6858)
			(drill 0.381)
			(layers "*.Cu" "*.Mask")
			(remove_unused_layers no)
			(net "SAS_B1_RX6P")
		)
		(pad "2A5" thru_hole circle
			(at 14 1.4 180)
			(size 0.6858 0.6858)
			(drill 0.381)
			(layers "*.Cu" "*.Mask")
			(remove_unused_layers no)
			(net "SAS_B1_RX6N")
		)
		(pad "2A6" thru_hole circle
			(at 14.750001 0.700001 180)
			(size 0.6858 0.6858)
			(drill 0.381)
			(layers "*.Cu" "*.Mask")
			(remove_unused_layers no)
			(net "GND")
		)
		(pad "2A7" thru_hole circle
			(at 15.499999 0 180)
			(size 0.6858 0.6858)
			(drill 0.381)
			(layers "*.Cu" "*.Mask")
			(remove_unused_layers no)
			(net "SAS_B1_RX8P")
		)
		(pad "2A8" thru_hole circle
			(at 16.250001 1.4 180)
			(size 0.6858 0.6858)
			(drill 0.381)
			(layers "*.Cu" "*.Mask")
			(remove_unused_layers no)
			(net "SAS_B1_RX8N")
		)
		(pad "2A9" thru_hole circle
			(at 16.999999 0.700001 180)
			(size 0.6858 0.6858)
			(drill 0.381)
			(layers "*.Cu" "*.Mask")
			(remove_unused_layers no)
			(net "GND")
		)
		(pad "2B1" thru_hole circle
			(at 11.000001 -3.8 180)
			(size 0.6858 0.6858)
			(drill 0.381)
			(layers "*.Cu" "*.Mask")
			(remove_unused_layers no)
			(net "Net_399")
		)
		(pad "2B2" thru_hole circle
			(at 11.749999 -2.4 180)
			(size 0.6858 0.6858)
			(drill 0.381)
			(layers "*.Cu" "*.Mask")
			(remove_unused_layers no)
			(net "Net_398")
		)
		(pad "2B3" thru_hole circle
			(at 12.5 -3.099999 180)
			(size 0.6858 0.6858)
			(drill 0.381)
			(layers "*.Cu" "*.Mask")
			(remove_unused_layers no)
			(net "GND")
		)
		(pad "2B4" thru_hole circle
			(at 13.249999 -3.8 180)
			(size 0.6858 0.6858)
			(drill 0.381)
			(layers "*.Cu" "*.Mask")
			(remove_unused_layers no)
			(net "SAS_B1_RX5P")
		)
		(pad "2B5" thru_hole circle
			(at 14 -2.4 180)
			(size 0.6858 0.6858)
			(drill 0.381)
			(layers "*.Cu" "*.Mask")
			(remove_unused_layers no)
			(net "SAS_B1_RX5N")
		)
		(pad "2B6" thru_hole circle
			(at 14.750001 -3.099999 180)
			(size 0.6858 0.6858)
			(drill 0.381)
			(layers "*.Cu" "*.Mask")
			(remove_unused_layers no)
			(net "GND")
		)
		(pad "2B7" thru_hole circle
			(at 15.499999 -3.8 180)
			(size 0.6858 0.6858)
			(drill 0.381)
			(layers "*.Cu" "*.Mask")
			(remove_unused_layers no)
			(net "SAS_B1_RX7P")
		)
		(pad "2B8" thru_hole circle
			(at 16.250001 -2.4 180)
			(size 0.6858 0.6858)
			(drill 0.381)
			(layers "*.Cu" "*.Mask")
			(remove_unused_layers no)
			(net "SAS_B1_RX7N")
		)
		(pad "2B9" thru_hole circle
			(at 16.999999 -3.099999 180)
			(size 0.6858 0.6858)
			(drill 0.381)
			(layers "*.Cu" "*.Mask")
			(remove_unused_layers no)
			(net "GND")
		)
		(pad "2C1" thru_hole circle
			(at 11.000001 -7.6 180)
			(size 0.6858 0.6858)
			(drill 0.381)
			(layers "*.Cu" "*.Mask")
			(remove_unused_layers no)
			(net "Net_397")
		)
		(pad "2C2" thru_hole circle
			(at 11.749999 -6.2 180)
			(size 0.6858 0.6858)
			(drill 0.381)
			(layers "*.Cu" "*.Mask")
			(remove_unused_layers no)
			(net "Net_396")
		)
		(pad "2C3" thru_hole circle
			(at 12.5 -6.899999 180)
			(size 0.6858 0.6858)
			(drill 0.381)
			(layers "*.Cu" "*.Mask")
			(remove_unused_layers no)
			(net "GND")
		)
		(pad "2C4" thru_hole circle
			(at 13.249999 -7.6 180)
			(size 0.6858 0.6858)
			(drill 0.381)
			(layers "*.Cu" "*.Mask")
			(remove_unused_layers no)
			(net "SAS_B1_TX6P")
		)
		(pad "2C5" thru_hole circle
			(at 14 -6.2 180)
			(size 0.6858 0.6858)
			(drill 0.381)
			(layers "*.Cu" "*.Mask")
			(remove_unused_layers no)
			(net "SAS_B1_TX6N")
		)
		(pad "2C6" thru_hole circle
			(at 14.750001 -6.899999 180)
			(size 0.6858 0.6858)
			(drill 0.381)
			(layers "*.Cu" "*.Mask")
			(remove_unused_layers no)
			(net "GND")
		)
		(pad "2C7" thru_hole circle
			(at 15.499999 -7.6 180)
			(size 0.6858 0.6858)
			(drill 0.381)
			(layers "*.Cu" "*.Mask")
			(remove_unused_layers no)
			(net "SAS_B1_TX8P")
		)
		(pad "2C8" thru_hole circle
			(at 16.250001 -6.2 180)
			(size 0.6858 0.6858)
			(drill 0.381)
			(layers "*.Cu" "*.Mask")
			(remove_unused_layers no)
			(net "SAS_B1_TX8N")
		)
		(pad "2C9" thru_hole circle
			(at 16.999999 -6.899999 180)
			(size 0.6858 0.6858)
			(drill 0.381)
			(layers "*.Cu" "*.Mask")
			(remove_unused_layers no)
			(net "GND")
		)
		(pad "2D1" thru_hole circle
			(at 11.000001 -11.4 180)
			(size 0.6858 0.6858)
			(drill 0.381)
			(layers "*.Cu" "*.Mask")
			(remove_unused_layers no)
			(net "Net_395")
		)
		(pad "2D2" thru_hole circle
			(at 11.749999 -10 180)
			(size 0.6858 0.6858)
			(drill 0.381)
			(layers "*.Cu" "*.Mask")
			(remove_unused_layers no)
			(net "Net_394")
		)
		(pad "2D3" thru_hole circle
			(at 12.5 -10.699999 180)
			(size 0.6858 0.6858)
			(drill 0.381)
			(layers "*.Cu" "*.Mask")
			(remove_unused_layers no)
			(net "GND")
		)
		(pad "2D4" thru_hole circle
			(at 13.249999 -11.4 180)
			(size 0.6858 0.6858)
			(drill 0.381)
			(layers "*.Cu" "*.Mask")
			(remove_unused_layers no)
			(net "SAS_B1_TX5P")
		)
		(pad "2D5" thru_hole circle
			(at 14 -10 180)
			(size 0.6858 0.6858)
			(drill 0.381)
			(layers "*.Cu" "*.Mask")
			(remove_unused_layers no)
			(net "SAS_B1_TX5N")
		)
		(pad "2D6" thru_hole circle
			(at 14.750001 -10.699999 180)
			(size 0.6858 0.6858)
			(drill 0.381)
			(layers "*.Cu" "*.Mask")
			(remove_unused_layers no)
			(net "GND")
		)
		(pad "2D7" thru_hole circle
			(at 15.499999 -11.4 180)
			(size 0.6858 0.6858)
			(drill 0.381)
			(layers "*.Cu" "*.Mask")
			(remove_unused_layers no)
			(net "SAS_B1_TX7P")
		)
		(pad "2D8" thru_hole circle
			(at 16.250001 -10 180)
			(size 0.6858 0.6858)
			(drill 0.381)
			(layers "*.Cu" "*.Mask")
			(remove_unused_layers no)
			(net "SAS_B1_TX7N")
		)
		(pad "2D9" thru_hole circle
			(at 16.999999 -10.699999 180)
			(size 0.6858 0.6858)
			(drill 0.381)
			(layers "*.Cu" "*.Mask")
			(remove_unused_layers no)
			(net "GND")
		)
		(pad "3" thru_hole circle
			(at 12.5 -13.109999 180)
			(size 1.1176 1.1176)
			(drill 0.6096)
			(layers "*.Cu" "*.Mask")
			(remove_unused_layers no)
			(net "GND")
		)
		(pad "4" thru_hole circle
			(at 16.999999 -13.109999 180)
			(size 1.1176 1.1176)
			(drill 0.6096)
			(layers "*.Cu" "*.Mask")
			(remove_unused_layers no)
			(net "GND")
		)
		(pad "5" thru_hole circle
			(at -2.5 0.700001 180)
			(size 1.1176 1.1176)
			(drill 0.6096)
			(layers "*.Cu" "*.Mask")
			(remove_unused_layers no)
			(net "GND")
		)
		(pad "6" thru_hole circle
			(at 8.500001 0.700001 180)
			(size 1.1176 1.1176)
			(drill 0.6096)
			(layers "*.Cu" "*.Mask")
			(remove_unused_layers no)
			(net "GND")
		)
		(pad "7" thru_hole circle
			(at 19.499999 0.700001 180)
			(size 1.1176 1.1176)
			(drill 0.6096)
			(layers "*.Cu" "*.Mask")
			(remove_unused_layers no)
			(net "GND")
		)
		(pad "8" thru_hole circle
			(at -2.5 14.01 180)
			(size 1.1176 1.1176)
			(drill 0.6096)
			(layers "*.Cu" "*.Mask")
			(remove_unused_layers no)
			(net "GND")
		)
		(pad "9" thru_hole circle
			(at 8.500001 14.01 180)
			(size 1.1176 1.1176)
			(drill 0.6096)
			(layers "*.Cu" "*.Mask")
			(remove_unused_layers no)
			(net "GND")
		)
		(pad "10" thru_hole circle
			(at 19.499999 14.01 180)
			(size 1.1176 1.1176)
			(drill 0.6096)
			(layers "*.Cu" "*.Mask")
			(remove_unused_layers no)
			(net "GND")
		)
	)
)
